(kicad_pcb
	(version 20260206)
	(generator "pcbnew")
	(generator_version "10.0")
	(general
		(thickness 1.6)
		(legacy_teardrops no)
	)
	(paper "A4")
	(title_block
		(title "peb — Lightning_PEB_BRD.brd")
		(comment 1 "Lightning (Wiwynn / Facebook NVMe JBOF) / footprints 1204-1210 of 2563")
	)
	(layers
		(0 "F.Cu" signal "TOP")
		(4 "In1.Cu" signal "L2GND")
		(6 "In2.Cu" signal "L3")
		(8 "In3.Cu" signal "L4VCC")
		(10 "In4.Cu" signal "L5VCC")
		(12 "In5.Cu" signal "L6")
		(14 "In6.Cu" signal "L7GND")
		(2 "B.Cu" signal "BOTTOM")
		(9 "F.Adhes" user "F.Adhesive")
		(11 "B.Adhes" user "B.Adhesive")
		(13 "F.Paste" user "Package Geometry/Pastemask Top")
		(15 "B.Paste" user "Package Geometry/Pastemask Bottom")
		(5 "F.SilkS" user "Ref Des/Silkscreen Top")
		(7 "B.SilkS" user "Ref Des/Silkscreen Bottom")
		(1 "F.Mask" user "Board Geometry/Soldermask Top")
		(3 "B.Mask" user "Board Geometry/Soldermask Bottom")
		(17 "Dwgs.User" user "User.Drawings")
		(19 "Cmts.User" user "User.Comments")
		(21 "Eco1.User" user "User.Eco1")
		(23 "Eco2.User" user "User.Eco2")
		(25 "Edge.Cuts" user "Board Geometry/Outline")
		(27 "Margin" user)
		(31 "F.CrtYd" user "Package Geometry/Place Bound Top")
		(29 "B.CrtYd" user "Package Geometry/Place Bound Bottom")
		(35 "F.Fab" user "Ref Des/Assembly Top")
		(33 "B.Fab" user "Ref Des/Assembly Bottom")
	)
	(footprint ""
		(layer "F.Cu")
		(at 72.90816 -37.9349 90)
		(property "Reference" "PR36"
			(at 0 0 90)
			(layer "F.SilkS")
			(hide yes)
			(effects
				(font
					(size 1.27 1.27)
				)
			)
		)
		(property "Value" "0R2J-2-GP"
			(at 0.064008 -3.993896 90)
			(unlocked yes)
			(layer "F.Fab")
			(hide yes)
			(effects
				(font
					(size 1.016 1.016)
					(thickness 0.1524)
				)
			)
		)
		(property "Device Type" "R402H16"
			(at 0.064008 -5.517896 90)
			(unlocked yes)
			(layer "F.Fab")
			(hide yes)
			(effects
				(font
					(size 1.016 1.016)
					(thickness 0.1524)
				)
			)
		)
		(duplicate_pad_numbers_are_jumpers no)
		(fp_line
			(start 0.508 -0.9398)
			(end -0.508 -0.9398)
			(stroke
				(width 0.1524)
				(type default)
			)
			(layer "F.SilkS")
		)
		(fp_line
			(start -0.508 -0.9398)
			(end -0.508 0.9398)
			(stroke
				(width 0.1524)
				(type default)
			)
			(layer "F.SilkS")
		)
		(fp_rect
			(start -0.508 0.9398)
			(end 0.508 -0.9398)
			(stroke
				(width 0)
				(type default)
			)
			(fill no)
			(layer "F.CrtYd")
		)
		(fp_rect
			(start -0.508 0.9398)
			(end 0.508 -0.9398)
			(stroke
				(width 0)
				(type default)
			)
			(fill no)
			(layer "F.Fab")
		)
		(pad "1" smd custom
			(at 0 -0.4445 90)
			(size 0.1397 0.1397)
			(layers "F.Cu" "F.Mask" "F.Paste")
			(net "P3V3_STBY_ROVP")
			(options
				(clearance outline)
				(anchor circle)
			)
			(primitives
				(gr_poly
					(pts
						(arc
							(start -0.1778 -0.2794)
							(mid -0.249642 -0.249642)
							(end -0.2794 -0.1778)
						)
						(arc
							(start -0.2794 0.1778)
							(mid -0.249642 0.249642)
							(end -0.1778 0.2794)
						)
						(arc
							(start 0.1778 0.2794)
							(mid 0.249642 0.249642)
							(end 0.2794 0.1778)
						)
						(arc
							(start 0.2794 -0.1778)
							(mid 0.249642 -0.249642)
							(end 0.1778 -0.2794)
						)
					)
					(width 0)
					(fill yes)
				)
			)
		)
		(pad "2" smd custom
			(at 0 0.4445 90)
			(size 0.1397 0.1397)
			(layers "F.Cu" "F.Mask" "F.Paste")
			(net "AGND_P3V3_STBY")
			(options
				(clearance outline)
				(anchor circle)
			)
			(primitives
				(gr_poly
					(pts
						(arc
							(start -0.1778 -0.2794)
							(mid -0.249642 -0.249642)
							(end -0.2794 -0.1778)
						)
						(arc
							(start -0.2794 0.1778)
							(mid -0.249642 0.249642)
							(end -0.1778 0.2794)
						)
						(arc
							(start 0.1778 0.2794)
							(mid 0.249642 0.249642)
							(end 0.2794 0.1778)
						)
						(arc
							(start 0.2794 -0.1778)
							(mid 0.249642 -0.249642)
							(end 0.1778 -0.2794)
						)
					)
					(width 0)
					(fill yes)
				)
			)
		)
	)
	(footprint ""
		(layer "F.Cu")
		(at 167.609774 -51.102768 180)
		(property "Reference" "Q34"
			(at 0 0 180)
			(layer "F.SilkS")
			(hide yes)
			(effects
				(font
					(size 1.27 1.27)
				)
			)
		)
		(property "Value" "2N7002K-1-GP"
			(at 0.127 -8.9662 180)
			(unlocked yes)
			(layer "F.Fab")
			(hide yes)
			(effects
				(font
					(size 1.016 1.016)
					(thickness 0.1524)
				)
			)
		)
		(property "Device Type" "SOT23DGS2D4H44"
			(at 0.127 -10.4902 180)
			(unlocked yes)
			(layer "F.Fab")
			(hide yes)
			(effects
				(font
					(size 1.016 1.016)
					(thickness 0.1524)
				)
			)
		)
		(duplicate_pad_numbers_are_jumpers no)
		(fp_line
			(start 1.651 1.778)
			(end 1.651 -1.778)
			(stroke
				(width 0.1524)
				(type default)
			)
			(layer "F.SilkS")
		)
		(fp_line
			(start 1.651 -1.778)
			(end -1.651 -1.778)
			(stroke
				(width 0.1524)
				(type default)
			)
			(layer "F.SilkS")
		)
		(fp_line
			(start -1.651 1.778)
			(end 1.651 1.778)
			(stroke
				(width 0.1524)
				(type default)
			)
			(layer "F.SilkS")
		)
		(fp_line
			(start -1.651 -1.778)
			(end -1.651 1.778)
			(stroke
				(width 0.1524)
				(type default)
			)
			(layer "F.SilkS")
		)
		(fp_poly
			(pts
				(xy -1.778 1.8796) (xy -1.778 -1.8796) (xy 1.778 -1.8796) (xy 1.778 1.8796)
			)
			(stroke
				(width 0)
				(type default)
			)
			(fill no)
			(layer "F.CrtYd")
		)
		(fp_poly
			(pts
				(xy -1.778 1.8796) (xy -1.778 -1.8796) (xy 1.778 -1.8796) (xy 1.778 1.8796)
			)
			(stroke
				(width 0)
				(type default)
			)
			(fill no)
			(layer "F.Fab")
		)
		(pad "D" smd custom
			(at 0 -0.9525 180)
			(size 0.1905 0.1905)
			(layers "F.Cu" "F.Mask" "F.Paste")
			(net "LED_Q_9")
			(options
				(clearance outline)
				(anchor circle)
			)
			(primitives
				(gr_poly
					(pts
						(arc
							(start -0.1778 0.5715)
							(mid -0.321484 0.511984)
							(end -0.381 0.3683)
						)
						(arc
							(start -0.381 -0.3683)
							(mid -0.321484 -0.511984)
							(end -0.1778 -0.5715)
						)
						(arc
							(start 0.1778 -0.5715)
							(mid 0.321484 -0.511984)
							(end 0.381 -0.3683)
						)
						(arc
							(start 0.381 0.3683)
							(mid 0.321484 0.511984)
							(end 0.1778 0.5715)
						)
					)
					(width 0)
					(fill yes)
				)
			)
		)
		(pad "G" smd custom
			(at -0.98425 0.9525 180)
			(size 0.1905 0.1905)
			(layers "F.Cu" "F.Mask" "F.Paste")
			(net "VS1_LED_R")
			(options
				(clearance outline)
				(anchor circle)
			)
			(primitives
				(gr_poly
					(pts
						(arc
							(start -0.1778 0.5715)
							(mid -0.321484 0.511984)
							(end -0.381 0.3683)
						)
						(arc
							(start -0.381 -0.3683)
							(mid -0.321484 -0.511984)
							(end -0.1778 -0.5715)
						)
						(arc
							(start 0.1778 -0.5715)
							(mid 0.321484 -0.511984)
							(end 0.381 -0.3683)
						)
						(arc
							(start 0.381 0.3683)
							(mid 0.321484 0.511984)
							(end 0.1778 0.5715)
						)
					)
					(width 0)
					(fill yes)
				)
			)
		)
		(pad "S" smd custom
			(at 0.98425 0.9525 180)
			(size 0.1905 0.1905)
			(layers "F.Cu" "F.Mask" "F.Paste")
			(net "GND")
			(options
				(clearance outline)
				(anchor circle)
			)
			(primitives
				(gr_poly
					(pts
						(arc
							(start -0.1778 0.5715)
							(mid -0.321484 0.511984)
							(end -0.381 0.3683)
						)
						(arc
							(start -0.381 -0.3683)
							(mid -0.321484 -0.511984)
							(end -0.1778 -0.5715)
						)
						(arc
							(start 0.1778 -0.5715)
							(mid 0.321484 -0.511984)
							(end 0.381 -0.3683)
						)
						(arc
							(start 0.381 0.3683)
							(mid 0.321484 0.511984)
							(end 0.1778 0.5715)
						)
					)
					(width 0)
					(fill yes)
				)
			)
		)
	)
	(footprint ""
		(layer "F.Cu")
		(at 340.233 -55.245 -90)
		(property "Reference" "PC221"
			(at 0 0 270)
			(layer "F.SilkS")
			(hide yes)
			(effects
				(font
					(size 1.27 1.27)
				)
			)
		)
		(property "Value" "SC22U25V6KX-GP-U"
			(at -2.860802 -5.279644 270)
			(unlocked yes)
			(layer "F.Fab")
			(hide yes)
			(effects
				(font
					(size 1.016 1.016)
					(thickness 0.1524)
				)
			)
		)
		(property "Device Type" "C1206-TO0D3H75"
			(at -2.860802 -6.803644 270)
			(unlocked yes)
			(layer "F.Fab")
			(hide yes)
			(effects
				(font
					(size 1.016 1.016)
					(thickness 0.1524)
				)
			)
		)
		(duplicate_pad_numbers_are_jumpers no)
		(fp_line
			(start -1.3081 2.3749)
			(end -1.3081 -2.3749)
			(stroke
				(width 0.1524)
				(type default)
			)
			(layer "F.SilkS")
		)
		(fp_line
			(start 1.3081 2.3749)
			(end -1.3081 2.3749)
			(stroke
				(width 0.1524)
				(type default)
			)
			(layer "F.SilkS")
		)
		(fp_line
			(start -1.3081 -2.3749)
			(end 1.3081 -2.3749)
			(stroke
				(width 0.1524)
				(type default)
			)
			(layer "F.SilkS")
		)
		(fp_line
			(start 1.3081 -2.3749)
			(end 1.3081 2.3749)
			(stroke
				(width 0.1524)
				(type default)
			)
			(layer "F.SilkS")
		)
		(fp_rect
			(start -0.8001 1.6002)
			(end 0.8001 -1.6002)
			(stroke
				(width 0)
				(type default)
			)
			(fill no)
			(layer "F.CrtYd")
		)
		(fp_poly
			(pts
				(xy -1.5621 2.4511) (xy -1.5621 1.6002) (xy 0.8001 1.6002) (xy 0.8001 -1.6002) (xy -0.8001 -1.6002)
				(xy -0.8001 1.5875) (xy -1.5621 1.5875) (xy -1.5621 -2.4511) (xy 1.5621 -2.4511) (xy 1.5621 2.4511)
			)
			(stroke
				(width 0)
				(type default)
			)
			(fill no)
			(layer "F.CrtYd")
		)
		(fp_rect
			(start -1.5621 2.4511)
			(end 1.5621 -2.4511)
			(stroke
				(width 0)
				(type default)
			)
			(fill no)
			(layer "F.Fab")
		)
		(pad "1" smd rect
			(at 0 -1.392936 270)
			(size 2.1082 1.4478)
			(layers "F.Cu" "F.Mask" "F.Paste")
			(net "P0V9_E_VIN")
		)
		(pad "2" smd rect
			(at 0 1.392936 270)
			(size 2.1082 1.4478)
			(layers "F.Cu" "F.Mask" "F.Paste")
			(net "GND")
		)
	)
	(footprint ""
		(layer "F.Cu")
		(at 227.9904 -190.5762)
		(property "Reference" "R9037"
			(at 0 0 0)
			(layer "F.SilkS")
			(hide yes)
			(effects
				(font
					(size 1.27 1.27)
				)
			)
		)
		(property "Value" "4K7R2F-GP"
			(at 0.064008 -3.993896 0)
			(unlocked yes)
			(layer "F.Fab")
			(hide yes)
			(effects
				(font
					(size 1.016 1.016)
					(thickness 0.1524)
				)
			)
		)
		(property "Device Type" "R402H16"
			(at 0.064008 -5.517896 0)
			(unlocked yes)
			(layer "F.Fab")
			(hide yes)
			(effects
				(font
					(size 1.016 1.016)
					(thickness 0.1524)
				)
			)
		)
		(duplicate_pad_numbers_are_jumpers no)
		(fp_line
			(start -0.508 -0.9398)
			(end -0.508 0.9398)
			(stroke
				(width 0.1524)
				(type default)
			)
			(layer "F.SilkS")
		)
		(fp_line
			(start 0.508 -0.9398)
			(end -0.508 -0.9398)
			(stroke
				(width 0.1524)
				(type default)
			)
			(layer "F.SilkS")
		)
		(fp_rect
			(start -0.508 0.9398)
			(end 0.508 -0.9398)
			(stroke
				(width 0)
				(type default)
			)
			(fill no)
			(layer "F.CrtYd")
		)
		(fp_rect
			(start -0.508 0.9398)
			(end 0.508 -0.9398)
			(stroke
				(width 0)
				(type default)
			)
			(fill no)
			(layer "F.Fab")
		)
		(pad "1" smd custom
			(at 0 -0.4445)
			(size 0.1397 0.1397)
			(layers "F.Cu" "F.Mask" "F.Paste")
			(net "SSD_PERST#8")
			(options
				(clearance outline)
				(anchor circle)
			)
			(primitives
				(gr_poly
					(pts
						(arc
							(start -0.1778 -0.2794)
							(mid -0.249642 -0.249642)
							(end -0.2794 -0.1778)
						)
						(arc
							(start -0.2794 0.1778)
							(mid -0.249642 0.249642)
							(end -0.1778 0.2794)
						)
						(arc
							(start 0.1778 0.2794)
							(mid 0.249642 0.249642)
							(end 0.2794 0.1778)
						)
						(arc
							(start 0.2794 -0.1778)
							(mid 0.249642 -0.249642)
							(end 0.1778 -0.2794)
						)
					)
					(width 0)
					(fill yes)
				)
			)
		)
		(pad "2" smd custom
			(at 0 0.4445)
			(size 0.1397 0.1397)
			(layers "F.Cu" "F.Mask" "F.Paste")
			(net "GND")
			(options
				(clearance outline)
				(anchor circle)
			)
			(primitives
				(gr_poly
					(pts
						(arc
							(start -0.1778 -0.2794)
							(mid -0.249642 -0.249642)
							(end -0.2794 -0.1778)
						)
						(arc
							(start -0.2794 0.1778)
							(mid -0.249642 0.249642)
							(end -0.1778 0.2794)
						)
						(arc
							(start 0.1778 0.2794)
							(mid 0.249642 0.249642)
							(end 0.2794 0.1778)
						)
						(arc
							(start 0.2794 -0.1778)
							(mid 0.249642 -0.249642)
							(end 0.1778 -0.2794)
						)
					)
					(width 0)
					(fill yes)
				)
			)
		)
	)
	(footprint ""
		(layer "F.Cu")
		(at 49.911 -178.816 -90)
		(property "Reference" "C709"
			(at 0 0 270)
			(layer "F.SilkS")
			(hide yes)
			(effects
				(font
					(size 1.27 1.27)
				)
			)
		)
		(property "Value" "SC220P50V3JN-GP"
			(at 0 -2.8194 270)
			(unlocked yes)
			(layer "F.Fab")
			(hide yes)
			(effects
				(font
					(size 1.016 1.016)
					(thickness 0.1524)
				)
			)
		)
		(property "Device Type" "C603H36"
			(at 0 -4.3434 270)
			(unlocked yes)
			(layer "F.Fab")
			(hide yes)
			(effects
				(font
					(size 1.016 1.016)
					(thickness 0.1524)
				)
			)
		)
		(duplicate_pad_numbers_are_jumpers no)
		(fp_line
			(start 0.508 0)
			(end -0.508 0)
			(stroke
				(width 0.2032)
				(type default)
			)
			(layer "F.SilkS")
		)
		(fp_rect
			(start -0.5842 1.3335)
			(end 0.5842 -1.3335)
			(stroke
				(width 0)
				(type default)
			)
			(fill no)
			(layer "F.CrtYd")
		)
		(fp_rect
			(start -0.5842 1.3335)
			(end 0.5842 -1.3335)
			(stroke
				(width 0)
				(type default)
			)
			(fill no)
			(layer "F.Fab")
		)
		(pad "1" smd custom
			(at 0 -0.762 270)
			(size 0.2159 0.2159)
			(layers "F.Cu" "F.Mask" "F.Paste")
			(net "BMC_I2C8_CLKBUF1_SDA_R")
			(options
				(clearance outline)
				(anchor circle)
			)
			(primitives
				(gr_poly
					(pts
						(arc
							(start -0.3302 -0.4318)
							(mid -0.402042 -0.402042)
							(end -0.4318 -0.3302)
						)
						(arc
							(start -0.4318 0.3302)
							(mid -0.402042 0.402042)
							(end -0.3302 0.4318)
						)
						(arc
							(start 0.3302 0.4318)
							(mid 0.402042 0.402042)
							(end 0.4318 0.3302)
						)
						(arc
							(start 0.4318 -0.3302)
							(mid 0.402042 -0.402042)
							(end 0.3302 -0.4318)
						)
					)
					(width 0)
					(fill yes)
				)
			)
		)
		(pad "2" smd custom
			(at 0 0.762 270)
			(size 0.2159 0.2159)
			(layers "F.Cu" "F.Mask" "F.Paste")
			(net "GND")
			(options
				(clearance outline)
				(anchor circle)
			)
			(primitives
				(gr_poly
					(pts
						(arc
							(start -0.3302 -0.4318)
							(mid -0.402042 -0.402042)
							(end -0.4318 -0.3302)
						)
						(arc
							(start -0.4318 0.3302)
							(mid -0.402042 0.402042)
							(end -0.3302 0.4318)
						)
						(arc
							(start 0.3302 0.4318)
							(mid 0.402042 0.402042)
							(end 0.4318 0.3302)
						)
						(arc
							(start 0.4318 -0.3302)
							(mid 0.402042 -0.402042)
							(end 0.3302 -0.4318)
						)
					)
					(width 0)
					(fill yes)
				)
			)
		)
	)
	(footprint ""
		(layer "F.Cu")
		(at 44.831 -145.161)
		(property "Reference" "TP230"
			(at 0 0 0)
			(layer "F.SilkS")
			(hide yes)
			(effects
				(font
					(size 1.27 1.27)
				)
			)
		)
		(property "Value" "TPAD28-2-GP"
			(at -0.0127 -1.6637 0)
			(unlocked yes)
			(layer "F.Fab")
			(hide yes)
			(effects
				(font
					(size 1.016 1.016)
					(thickness 0.1524)
				)
			)
		)
		(property "Device Type" "TPAD28"
			(at -0.0127 -3.1877 0)
			(unlocked yes)
			(layer "F.Fab")
			(hide yes)
			(effects
				(font
					(size 1.016 1.016)
					(thickness 0.1524)
				)
			)
		)
		(duplicate_pad_numbers_are_jumpers no)
		(fp_poly
			(pts
				(arc
					(start 0.3556 0)
					(mid -0.3556 0)
					(end 0.3556 0)
				)
			)
			(stroke
				(width 0)
				(type default)
			)
			(fill no)
			(layer "F.CrtYd")
		)
		(fp_poly
			(pts
				(arc
					(start 0.6096 0)
					(mid -0.6096 0)
					(end 0.6096 0)
				)
			)
			(stroke
				(width 0)
				(type default)
			)
			(fill no)
			(layer "F.Fab")
		)
		(pad "1" smd circle
			(at 0 0)
			(size 0.7112 0.7112)
			(layers "F.Cu" "F.Mask" "F.Paste")
			(net "TP_GPIOP1")
		)
	)
	(footprint ""
		(layer "F.Cu")
		(at 334.01 -71.247 180)
		(property "Reference" "PR157"
			(at 0 0 180)
			(layer "F.SilkS")
			(hide yes)
			(effects
				(font
					(size 1.27 1.27)
				)
			)
		)
		(property "Value" "51KR2F-L-GP"
			(at 0.064008 -3.993896 180)
			(unlocked yes)
			(layer "F.Fab")
			(hide yes)
			(effects
				(font
					(size 1.016 1.016)
					(thickness 0.1524)
				)
			)
		)
		(property "Device Type" "R402H16"
			(at 0.064008 -5.517896 180)
			(unlocked yes)
			(layer "F.Fab")
			(hide yes)
			(effects
				(font
					(size 1.016 1.016)
					(thickness 0.1524)
				)
			)
		)
		(duplicate_pad_numbers_are_jumpers no)
		(fp_line
			(start 0.508 -0.9398)
			(end -0.508 -0.9398)
			(stroke
				(width 0.1524)
				(type default)
			)
			(layer "F.SilkS")
		)
		(fp_line
			(start -0.508 -0.9398)
			(end -0.508 0.9398)
			(stroke
				(width 0.1524)
				(type default)
			)
			(layer "F.SilkS")
		)
		(fp_rect
			(start -0.508 0.9398)
			(end 0.508 -0.9398)
			(stroke
				(width 0)
				(type default)
			)
			(fill no)
			(layer "F.CrtYd")
		)
		(fp_rect
			(start -0.508 0.9398)
			(end 0.508 -0.9398)
			(stroke
				(width 0)
				(type default)
			)
			(fill no)
			(layer "F.Fab")
		)
		(pad "1" smd custom
			(at 0 -0.4445 180)
			(size 0.1397 0.1397)
			(layers "F.Cu" "F.Mask" "F.Paste")
			(net "P0V9_E_EN")
			(options
				(clearance outline)
				(anchor circle)
			)
			(primitives
				(gr_poly
					(pts
						(arc
							(start -0.1778 -0.2794)
							(mid -0.249642 -0.249642)
							(end -0.2794 -0.1778)
						)
						(arc
							(start -0.2794 0.1778)
							(mid -0.249642 0.249642)
							(end -0.1778 0.2794)
						)
						(arc
							(start 0.1778 0.2794)
							(mid 0.249642 0.249642)
							(end 0.2794 0.1778)
						)
						(arc
							(start 0.2794 -0.1778)
							(mid 0.249642 -0.249642)
							(end 0.1778 -0.2794)
						)
					)
					(width 0)
					(fill yes)
				)
			)
		)
		(pad "2" smd custom
			(at 0 0.4445 180)
			(size 0.1397 0.1397)
			(layers "F.Cu" "F.Mask" "F.Paste")
			(net "GND")
			(options
				(clearance outline)
				(anchor circle)
			)
			(primitives
				(gr_poly
					(pts
						(arc
							(start -0.1778 -0.2794)
							(mid -0.249642 -0.249642)
							(end -0.2794 -0.1778)
						)
						(arc
							(start -0.2794 0.1778)
							(mid -0.249642 0.249642)
							(end -0.1778 0.2794)
						)
						(arc
							(start 0.1778 0.2794)
							(mid 0.249642 0.249642)
							(end 0.2794 0.1778)
						)
						(arc
							(start 0.2794 -0.1778)
							(mid 0.249642 -0.249642)
							(end 0.1778 -0.2794)
						)
					)
					(width 0)
					(fill yes)
				)
			)
		)
	)
)
